(kicad_pcb
	(version 20241229)
	(generator "pcbnew")
	(generator_version "9.0")
	(general
		(thickness 1.62)
		(legacy_teardrops no)
	)
	(paper "A3")
	(title_block
		(title "COM Express 7 Baseboard")
		(date "2025-02-04")
		(rev "1.1.2")
		(company "Antmicro Ltd")
		(comment 1 "www.antmicro.com")
		(comment 9 "footprint 489 of 802 (J12), pads 84-124 of 450")
	)
	(layers
		(0 "F.Cu" signal)
		(4 "In1.Cu" signal)
		(6 "In2.Cu" signal)
		(8 "In3.Cu" signal)
		(10 "In4.Cu" signal)
		(12 "In5.Cu" signal)
		(14 "In6.Cu" signal)
		(2 "B.Cu" signal)
		(9 "F.Adhes" user "F.Adhesive")
		(11 "B.Adhes" user "B.Adhesive")
		(13 "F.Paste" user)
		(15 "B.Paste" user)
		(5 "F.SilkS" user "F.Silkscreen")
		(7 "B.SilkS" user "B.Silkscreen")
		(1 "F.Mask" user)
		(3 "B.Mask" user)
		(17 "Dwgs.User" user "User.Drawings")
		(19 "Cmts.User" user "User.Comments")
		(21 "Eco1.User" user "User.Eco1")
		(23 "Eco2.User" user "User.Eco2")
		(25 "Edge.Cuts" user)
		(27 "Margin" user)
		(31 "F.CrtYd" user "F.Courtyard")
		(29 "B.CrtYd" user "B.Courtyard")
		(35 "F.Fab" user)
		(33 "B.Fab" user)
	)
	(footprint "antmicro-footprints:EPT_401-51501-51"
		(layer "F.Cu")
		(at 203.275 159.81)
		(property "Reference" "J12"
			(at 30.975 -10.45 0)
			(layer "F.SilkS")
			(effects
				(font
					(size 0.7 0.7)
					(thickness 0.15)
				)
				(justify right top)
			)
		)
		(property "Value" "Plug_Bus_CE7_EPT_401-51501-51"
			(at -3.225 52.665 0)
			(layer "F.Fab")
			(hide yes)
			(effects
				(font
					(size 0.7 0.7)
					(thickness 0.15)
				)
				(justify left top)
			)
		)
		(property "Datasheet" "https://www.farnell.com/datasheets/1905093.pdf"
			(at 0 0 0)
			(layer "F.Fab")
			(hide yes)
			(effects
				(font
					(size 1.27 1.27)
					(thickness 0.15)
				)
			)
		)
		(property "Author" "Antmicro"
			(at 406.55 319.62 0)
			(layer "F.Fab")
			(hide yes)
			(effects
				(font
					(size 1 1)
					(thickness 0.15)
				)
			)
		)
		(property "License" "Apache-2.0"
			(at 406.55 319.62 0)
			(layer "F.Fab")
			(hide yes)
			(effects
				(font
					(size 1 1)
					(thickness 0.15)
				)
			)
		)
		(property "MPN" "401-51501-51"
			(at 406.55 319.62 0)
			(layer "F.Fab")
			(hide yes)
			(effects
				(font
					(size 1 1)
					(thickness 0.15)
				)
			)
		)
		(property "Manufacturer" "ept"
			(at 406.55 319.62 0)
			(layer "F.Fab")
			(hide yes)
			(effects
				(font
					(size 1 1)
					(thickness 0.15)
				)
			)
		)
		(sheetname "Com Express 7 Interfaces")
		(sheetfile "com_express_7_interfaces.kicad_sch")
		(attr smd)
		(pad "A79" smd rect
			(at 11.75 8.875)
			(size 0.3 1.75)
			(layers "F.Cu" "F.Mask" "F.Paste")
			(net 1 "GND")
			(pinfunction "GND")
			(pintype "passive")
			(teardrops
				(best_length_ratio 0.2)
				(max_length 1)
				(best_width_ratio 0.9)
				(max_width 2)
				(curved_edges yes)
				(filter_ratio 0.9)
				(enabled yes)
				(allow_two_segments yes)
				(prefer_zone_connections yes)
			)
		)
		(pad "A80" smd rect
			(at 12.25 8.875)
			(size 0.3 1.75)
			(layers "F.Cu" "F.Mask" "F.Paste")
			(net 1 "GND")
			(pinfunction "GND(FIXED)")
			(pintype "passive")
			(teardrops
				(best_length_ratio 0.2)
				(max_length 1)
				(best_width_ratio 0.9)
				(max_width 2)
				(curved_edges yes)
				(filter_ratio 0.9)
				(enabled yes)
				(allow_two_segments yes)
				(prefer_zone_connections yes)
			)
		)
		(pad "A81" smd rect
			(at 12.75 8.875)
			(size 0.3 1.75)
			(layers "F.Cu" "F.Mask" "F.Paste")
			(net 330 "/Com Express 7 Interfaces/PCIe_{B2Ax4}.TX3+")
			(pinfunction "PCIE_TX11+")
			(pintype "output")
			(teardrops
				(best_length_ratio 0.2)
				(max_length 1)
				(best_width_ratio 0.9)
				(max_width 2)
				(curved_edges yes)
				(filter_ratio 0.9)
				(enabled yes)
				(allow_two_segments yes)
				(prefer_zone_connections yes)
			)
		)
		(pad "A82" smd rect
			(at 13.25 8.875)
			(size 0.3 1.75)
			(layers "F.Cu" "F.Mask" "F.Paste")
			(net 331 "/Com Express 7 Interfaces/PCIe_{B2Ax4}.TX3-")
			(pinfunction "PCIE_TX11-")
			(pintype "output")
			(teardrops
				(best_length_ratio 0.2)
				(max_length 1)
				(best_width_ratio 0.9)
				(max_width 2)
				(curved_edges yes)
				(filter_ratio 0.9)
				(enabled yes)
				(allow_two_segments yes)
				(prefer_zone_connections yes)
			)
		)
		(pad "A83" smd rect
			(at 13.75 8.875)
			(size 0.3 1.75)
			(layers "F.Cu" "F.Mask" "F.Paste")
			(net 1 "GND")
			(pinfunction "GND")
			(pintype "passive")
			(teardrops
				(best_length_ratio 0.2)
				(max_length 1)
				(best_width_ratio 0.9)
				(max_width 2)
				(curved_edges yes)
				(filter_ratio 0.9)
				(enabled yes)
				(allow_two_segments yes)
				(prefer_zone_connections yes)
			)
		)
		(pad "A84" smd rect
			(at 14.25 8.875)
			(size 0.3 1.75)
			(layers "F.Cu" "F.Mask" "F.Paste")
			(net 332 "unconnected-(J12A-NCSI_TX_EN-PadA84)")
			(pinfunction "NCSI_TX_EN")
			(pintype "output+no_connect")
			(teardrops
				(best_length_ratio 0.2)
				(max_length 1)
				(best_width_ratio 0.9)
				(max_width 2)
				(curved_edges yes)
				(filter_ratio 0.9)
				(enabled yes)
				(allow_two_segments yes)
				(prefer_zone_connections yes)
			)
		)
		(pad "A85" smd rect
			(at 14.75 8.875)
			(size 0.3 1.75)
			(layers "F.Cu" "F.Mask" "F.Paste")
			(net 333 "/Com Express 7 Interfaces/SDIO.DAT3")
			(pinfunction "GPI3")
			(pintype "input")
			(teardrops
				(best_length_ratio 0.2)
				(max_length 1)
				(best_width_ratio 0.9)
				(max_width 2)
				(curved_edges yes)
				(filter_ratio 0.9)
				(enabled yes)
				(allow_two_segments yes)
				(prefer_zone_connections yes)
			)
		)
		(pad "A86" smd rect
			(at 15.25 8.875)
			(size 0.3 1.75)
			(layers "F.Cu" "F.Mask" "F.Paste")
			(net 334 "unconnected-(J12H-RSVD-PadA86)")
			(pinfunction "RSVD")
			(pintype "no_connect")
			(teardrops
				(best_length_ratio 0.2)
				(max_length 1)
				(best_width_ratio 0.9)
				(max_width 2)
				(curved_edges yes)
				(filter_ratio 0.9)
				(enabled yes)
				(allow_two_segments yes)
				(prefer_zone_connections yes)
			)
		)
		(pad "A87" smd rect
			(at 15.75 8.875)
			(size 0.3 1.75)
			(layers "F.Cu" "F.Mask" "F.Paste")
			(net 335 "unconnected-(J12H-RSVD-PadA87)")
			(pinfunction "RSVD")
			(pintype "no_connect")
			(teardrops
				(best_length_ratio 0.2)
				(max_length 1)
				(best_width_ratio 0.9)
				(max_width 2)
				(curved_edges yes)
				(filter_ratio 0.9)
				(enabled yes)
				(allow_two_segments yes)
				(prefer_zone_connections yes)
			)
		)
		(pad "A88" smd rect
			(at 16.25 8.875)
			(size 0.3 1.75)
			(layers "F.Cu" "F.Mask" "F.Paste")
			(net 336 "/Com Express 7 Interfaces/PCIE_{REF}.CK+")
			(pinfunction "PCIE_CK_REF+")
			(pintype "output")
			(teardrops
				(best_length_ratio 0.2)
				(max_length 1)
				(best_width_ratio 0.9)
				(max_width 2)
				(curved_edges yes)
				(filter_ratio 0.9)
				(enabled yes)
				(allow_two_segments yes)
				(prefer_zone_connections yes)
			)
		)
		(pad "A89" smd rect
			(at 16.75 8.875)
			(size 0.3 1.75)
			(layers "F.Cu" "F.Mask" "F.Paste")
			(net 337 "/Com Express 7 Interfaces/PCIE_{REF}.CK-")
			(pinfunction "PCIE_CK_REF-")
			(pintype "output")
			(teardrops
				(best_length_ratio 0.2)
				(max_length 1)
				(best_width_ratio 0.9)
				(max_width 2)
				(curved_edges yes)
				(filter_ratio 0.9)
				(enabled yes)
				(allow_two_segments yes)
				(prefer_zone_connections yes)
			)
		)
		(pad "A90" smd rect
			(at 17.25 8.875)
			(size 0.3 1.75)
			(layers "F.Cu" "F.Mask" "F.Paste")
			(net 1 "GND")
			(pinfunction "GND(FIXED)")
			(pintype "passive")
			(teardrops
				(best_length_ratio 0.2)
				(max_length 1)
				(best_width_ratio 0.9)
				(max_width 2)
				(curved_edges yes)
				(filter_ratio 0.9)
				(enabled yes)
				(allow_two_segments yes)
				(prefer_zone_connections yes)
			)
		)
		(pad "A91" smd rect
			(at 17.75 8.875)
			(size 0.3 1.75)
			(layers "F.Cu" "F.Mask" "F.Paste")
			(net 139 "/Com Express 7 MGMT/SPI_POWER")
			(pinfunction "SPI_POWER")
			(pintype "power_out")
			(teardrops
				(best_length_ratio 0.2)
				(max_length 1)
				(best_width_ratio 0.9)
				(max_width 2)
				(curved_edges yes)
				(filter_ratio 0.9)
				(enabled yes)
				(allow_two_segments yes)
				(prefer_zone_connections yes)
			)
		)
		(pad "A92" smd rect
			(at 18.25 8.875)
			(size 0.3 1.75)
			(layers "F.Cu" "F.Mask" "F.Paste")
			(net 338 "/Com Express 7 MGMT/SPI.MISO")
			(pinfunction "SPI_MISO")
			(pintype "input")
			(teardrops
				(best_length_ratio 0.2)
				(max_length 1)
				(best_width_ratio 0.9)
				(max_width 2)
				(curved_edges yes)
				(filter_ratio 0.9)
				(enabled yes)
				(allow_two_segments yes)
				(prefer_zone_connections yes)
			)
		)
		(pad "A93" smd rect
			(at 18.75 8.875)
			(size 0.3 1.75)
			(layers "F.Cu" "F.Mask" "F.Paste")
			(net 339 "/Com Express 7 Interfaces/SDIO.CLK")
			(pinfunction "GPO0")
			(pintype "output")
			(teardrops
				(best_length_ratio 0.2)
				(max_length 1)
				(best_width_ratio 0.9)
				(max_width 2)
				(curved_edges yes)
				(filter_ratio 0.9)
				(enabled yes)
				(allow_two_segments yes)
				(prefer_zone_connections yes)
			)
		)
		(pad "A94" smd rect
			(at 19.25 8.875)
			(size 0.3 1.75)
			(layers "F.Cu" "F.Mask" "F.Paste")
			(net 340 "/Com Express 7 MGMT/SPI.CLK")
			(pinfunction "SPI_CLK")
			(pintype "output")
			(teardrops
				(best_length_ratio 0.2)
				(max_length 1)
				(best_width_ratio 0.9)
				(max_width 2)
				(curved_edges yes)
				(filter_ratio 0.9)
				(enabled yes)
				(allow_two_segments yes)
				(prefer_zone_connections yes)
			)
		)
		(pad "A95" smd rect
			(at 19.75 8.875)
			(size 0.3 1.75)
			(layers "F.Cu" "F.Mask" "F.Paste")
			(net 341 "/Com Express 7 MGMT/SPI.MOSI")
			(pinfunction "SPI_MOSI")
			(pintype "output")
			(teardrops
				(best_length_ratio 0.2)
				(max_length 1)
				(best_width_ratio 0.9)
				(max_width 2)
				(curved_edges yes)
				(filter_ratio 0.9)
				(enabled yes)
				(allow_two_segments yes)
				(prefer_zone_connections yes)
			)
		)
		(pad "A96" smd rect
			(at 20.25 8.875)
			(size 0.3 1.75)
			(layers "F.Cu" "F.Mask" "F.Paste")
			(net 342 "Net-(J12D-TPM_PP)")
			(pinfunction "TPM_PP")
			(pintype "input")
			(teardrops
				(best_length_ratio 0.2)
				(max_length 1)
				(best_width_ratio 0.9)
				(max_width 2)
				(curved_edges yes)
				(filter_ratio 0.9)
				(enabled yes)
				(allow_two_segments yes)
				(prefer_zone_connections yes)
			)
		)
		(pad "A97" smd rect
			(at 20.75 8.875)
			(size 0.3 1.75)
			(layers "F.Cu" "F.Mask" "F.Paste")
			(net 343 "Net-(J12D-~{TYPE10})")
			(pinfunction "~{TYPE10}")
			(pintype "passive")
			(teardrops
				(best_length_ratio 0.2)
				(max_length 1)
				(best_width_ratio 0.9)
				(max_width 2)
				(curved_edges yes)
				(filter_ratio 0.9)
				(enabled yes)
				(allow_two_segments yes)
				(prefer_zone_connections yes)
			)
		)
		(pad "A98" smd rect
			(at 21.25 8.875)
			(size 0.3 1.75)
			(layers "F.Cu" "F.Mask" "F.Paste")
			(net 344 "/Com Express 7 MGMT/SER0.TX")
			(pinfunction "SER0_TX")
			(pintype "output")
			(teardrops
				(best_length_ratio 0.2)
				(max_length 1)
				(best_width_ratio 0.9)
				(max_width 2)
				(curved_edges yes)
				(filter_ratio 0.9)
				(enabled yes)
				(allow_two_segments yes)
				(prefer_zone_connections yes)
			)
		)
		(pad "A99" smd rect
			(at 21.75 8.875)
			(size 0.3 1.75)
			(layers "F.Cu" "F.Mask" "F.Paste")
			(net 345 "/Com Express 7 MGMT/SER0.RX")
			(pinfunction "SER0_RX")
			(pintype "input")
			(teardrops
				(best_length_ratio 0.2)
				(max_length 1)
				(best_width_ratio 0.9)
				(max_width 2)
				(curved_edges yes)
				(filter_ratio 0.9)
				(enabled yes)
				(allow_two_segments yes)
				(prefer_zone_connections yes)
			)
		)
		(pad "A100" smd rect
			(at 22.25 8.875)
			(size 0.3 1.75)
			(layers "F.Cu" "F.Mask" "F.Paste")
			(net 1 "GND")
			(pinfunction "GND(FIXED)")
			(pintype "passive")
			(teardrops
				(best_length_ratio 0.2)
				(max_length 1)
				(best_width_ratio 0.9)
				(max_width 2)
				(curved_edges yes)
				(filter_ratio 0.9)
				(enabled yes)
				(allow_two_segments yes)
				(prefer_zone_connections yes)
			)
		)
		(pad "A101" smd rect
			(at 22.75 8.875)
			(size 0.3 1.75)
			(layers "F.Cu" "F.Mask" "F.Paste")
			(net 207 "/Backplane/UART.TX")
			(pinfunction "SER1_TX")
			(pintype "output")
			(teardrops
				(best_length_ratio 0.2)
				(max_length 1)
				(best_width_ratio 0.9)
				(max_width 2)
				(curved_edges yes)
				(filter_ratio 0.9)
				(enabled yes)
				(allow_two_segments yes)
				(prefer_zone_connections yes)
			)
		)
		(pad "A102" smd rect
			(at 23.25 8.875)
			(size 0.3 1.75)
			(layers "F.Cu" "F.Mask" "F.Paste")
			(net 208 "/Backplane/UART.RX")
			(pinfunction "SER1_RX")
			(pintype "input")
			(teardrops
				(best_length_ratio 0.2)
				(max_length 1)
				(best_width_ratio 0.9)
				(max_width 2)
				(curved_edges yes)
				(filter_ratio 0.9)
				(enabled yes)
				(allow_two_segments yes)
				(prefer_zone_connections yes)
			)
		)
		(pad "A103" smd rect
			(at 23.75 8.875)
			(size 0.3 1.75)
			(layers "F.Cu" "F.Mask" "F.Paste")
			(net 346 "unconnected-(J12D-~{LID}-PadA103)")
			(pinfunction "~{LID}")
			(pintype "input+no_connect")
			(teardrops
				(best_length_ratio 0.2)
				(max_length 1)
				(best_width_ratio 0.9)
				(max_width 2)
				(curved_edges yes)
				(filter_ratio 0.9)
				(enabled yes)
				(allow_two_segments yes)
				(prefer_zone_connections yes)
			)
		)
		(pad "A104" smd rect
			(at 24.25 8.875)
			(size 0.3 1.75)
			(layers "F.Cu" "F.Mask" "F.Paste")
			(net 65 "+12V")
			(pinfunction "VCC_12V")
			(pintype "power_in")
			(teardrops
				(best_length_ratio 0.2)
				(max_length 1)
				(best_width_ratio 0.9)
				(max_width 2)
				(curved_edges yes)
				(filter_ratio 0.9)
				(enabled yes)
				(allow_two_segments yes)
				(prefer_zone_connections yes)
			)
		)
		(pad "A105" smd rect
			(at 24.75 8.875)
			(size 0.3 1.75)
			(layers "F.Cu" "F.Mask" "F.Paste")
			(net 65 "+12V")
			(pinfunction "VCC_12V")
			(pintype "passive")
			(teardrops
				(best_length_ratio 0.2)
				(max_length 1)
				(best_width_ratio 0.9)
				(max_width 2)
				(curved_edges yes)
				(filter_ratio 0.9)
				(enabled yes)
				(allow_two_segments yes)
				(prefer_zone_connections yes)
			)
		)
		(pad "A106" smd rect
			(at 25.25 8.875)
			(size 0.3 1.75)
			(layers "F.Cu" "F.Mask" "F.Paste")
			(net 65 "+12V")
			(pinfunction "VCC_12V")
			(pintype "passive")
			(teardrops
				(best_length_ratio 0.2)
				(max_length 1)
				(best_width_ratio 0.9)
				(max_width 2)
				(curved_edges yes)
				(filter_ratio 0.9)
				(enabled yes)
				(allow_two_segments yes)
				(prefer_zone_connections yes)
			)
		)
		(pad "A107" smd rect
			(at 25.75 8.875)
			(size 0.3 1.75)
			(layers "F.Cu" "F.Mask" "F.Paste")
			(net 65 "+12V")
			(pinfunction "VCC_12V")
			(pintype "passive")
			(teardrops
				(best_length_ratio 0.2)
				(max_length 1)
				(best_width_ratio 0.9)
				(max_width 2)
				(curved_edges yes)
				(filter_ratio 0.9)
				(enabled yes)
				(allow_two_segments yes)
				(prefer_zone_connections yes)
			)
		)
		(pad "A108" smd rect
			(at 26.25 8.875)
			(size 0.3 1.75)
			(layers "F.Cu" "F.Mask" "F.Paste")
			(net 65 "+12V")
			(pinfunction "VCC_12V")
			(pintype "passive")
			(teardrops
				(best_length_ratio 0.2)
				(max_length 1)
				(best_width_ratio 0.9)
				(max_width 2)
				(curved_edges yes)
				(filter_ratio 0.9)
				(enabled yes)
				(allow_two_segments yes)
				(prefer_zone_connections yes)
			)
		)
		(pad "A109" smd rect
			(at 26.75 8.875)
			(size 0.3 1.75)
			(layers "F.Cu" "F.Mask" "F.Paste")
			(net 65 "+12V")
			(pinfunction "VCC_12V")
			(pintype "passive")
			(teardrops
				(best_length_ratio 0.2)
				(max_length 1)
				(best_width_ratio 0.9)
				(max_width 2)
				(curved_edges yes)
				(filter_ratio 0.9)
				(enabled yes)
				(allow_two_segments yes)
				(prefer_zone_connections yes)
			)
		)
		(pad "A110" smd rect
			(at 27.25 8.875)
			(size 0.3 1.75)
			(layers "F.Cu" "F.Mask" "F.Paste")
			(net 1 "GND")
			(pinfunction "GND(FIXED)")
			(pintype "passive")
			(teardrops
				(best_length_ratio 0.2)
				(max_length 1)
				(best_width_ratio 0.9)
				(max_width 2)
				(curved_edges yes)
				(filter_ratio 0.9)
				(enabled yes)
				(allow_two_segments yes)
				(prefer_zone_connections yes)
			)
		)
		(pad "B1" smd rect
			(at -27.25 3.325)
			(size 0.3 1.75)
			(layers "F.Cu" "F.Mask" "F.Paste")
			(net 1 "GND")
			(pinfunction "GND(FIXED)")
			(pintype "passive")
			(teardrops
				(best_length_ratio 0.2)
				(max_length 1)
				(best_width_ratio 0.9)
				(max_width 2)
				(curved_edges yes)
				(filter_ratio 0.9)
				(enabled yes)
				(allow_two_segments yes)
				(prefer_zone_connections yes)
			)
		)
		(pad "B2" smd rect
			(at -26.75 3.325)
			(size 0.3 1.75)
			(layers "F.Cu" "F.Mask" "F.Paste")
			(net 347 "/2xUSB3.0+RJ45/~{GBE0_ACT}")
			(pinfunction "~{GBE0_ACT}")
			(pintype "output")
			(teardrops
				(best_length_ratio 0.2)
				(max_length 1)
				(best_width_ratio 0.9)
				(max_width 2)
				(curved_edges yes)
				(filter_ratio 0.9)
				(enabled yes)
				(allow_two_segments yes)
				(prefer_zone_connections yes)
			)
		)
		(pad "B3" smd rect
			(at -26.25 3.325)
			(size 0.3 1.75)
			(layers "F.Cu" "F.Mask" "F.Paste")
			(net 348 "Net-(J12D-~{LPC_FRAME}{slash}~{ESPI_CS0})")
			(pinfunction "~{LPC_FRAME}/~{ESPI_CS0}")
			(pintype "bidirectional")
			(teardrops
				(best_length_ratio 0.2)
				(max_length 1)
				(best_width_ratio 0.9)
				(max_width 2)
				(curved_edges yes)
				(filter_ratio 0.9)
				(enabled yes)
				(allow_two_segments yes)
				(prefer_zone_connections yes)
			)
		)
		(pad "B4" smd rect
			(at -25.75 3.325)
			(size 0.3 1.75)
			(layers "F.Cu" "F.Mask" "F.Paste")
			(net 349 "Net-(J12D-LPC_AD0{slash}ESPI_IO_0)")
			(pinfunction "LPC_AD0/ESPI_IO_0")
			(pintype "bidirectional")
			(teardrops
				(best_length_ratio 0.2)
				(max_length 1)
				(best_width_ratio 0.9)
				(max_width 2)
				(curved_edges yes)
				(filter_ratio 0.9)
				(enabled yes)
				(allow_two_segments yes)
				(prefer_zone_connections yes)
			)
		)
		(pad "B5" smd rect
			(at -25.25 3.325)
			(size 0.3 1.75)
			(layers "F.Cu" "F.Mask" "F.Paste")
			(net 350 "Net-(J12D-LPC_AD1{slash}ESPI_IO_1)")
			(pinfunction "LPC_AD1/ESPI_IO_1")
			(pintype "bidirectional")
			(teardrops
				(best_length_ratio 0.2)
				(max_length 1)
				(best_width_ratio 0.9)
				(max_width 2)
				(curved_edges yes)
				(filter_ratio 0.9)
				(enabled yes)
				(allow_two_segments yes)
				(prefer_zone_connections yes)
			)
		)
		(pad "B6" smd rect
			(at -24.75 3.325)
			(size 0.3 1.75)
			(layers "F.Cu" "F.Mask" "F.Paste")
			(net 351 "Net-(J12D-LPC_AD2{slash}ESPI_IO_2)")
			(pinfunction "LPC_AD2/ESPI_IO_2")
			(pintype "bidirectional")
			(teardrops
				(best_length_ratio 0.2)
				(max_length 1)
				(best_width_ratio 0.9)
				(max_width 2)
				(curved_edges yes)
				(filter_ratio 0.9)
				(enabled yes)
				(allow_two_segments yes)
				(prefer_zone_connections yes)
			)
		)
		(pad "B7" smd rect
			(at -24.25 3.325)
			(size 0.3 1.75)
			(layers "F.Cu" "F.Mask" "F.Paste")
			(net 352 "Net-(J12D-LPC_AD3{slash}ESPI_IO_3)")
			(pinfunction "LPC_AD3/ESPI_IO_3")
			(pintype "bidirectional")
			(teardrops
				(best_length_ratio 0.2)
				(max_length 1)
				(best_width_ratio 0.9)
				(max_width 2)
				(curved_edges yes)
				(filter_ratio 0.9)
				(enabled yes)
				(allow_two_segments yes)
				(prefer_zone_connections yes)
			)
		)
		(pad "B8" smd rect
			(at -23.75 3.325)
			(size 0.3 1.75)
			(layers "F.Cu" "F.Mask" "F.Paste")
			(net 353 "Net-(J12D-~{LPC_DRQ0}{slash}~{ESPI_ALERT0})")
			(pinfunction "~{LPC_DRQ0}/~{ESPI_ALERT0}")
			(pintype "input")
			(teardrops
				(best_length_ratio 0.2)
				(max_length 1)
				(best_width_ratio 0.9)
				(max_width 2)
				(curved_edges yes)
				(filter_ratio 0.9)
				(enabled yes)
				(allow_two_segments yes)
				(prefer_zone_connections yes)
			)
		)
		(pad "B9" smd rect
			(at -23.25 3.325)
			(size 0.3 1.75)
			(layers "F.Cu" "F.Mask" "F.Paste")
			(net 354 "Net-(J12D-~{LPC_DRQ1}{slash}~{ESPI_ALERT1})")
			(pinfunction "~{LPC_DRQ1}/~{ESPI_ALERT1}")
			(pintype "input")
			(teardrops
				(best_length_ratio 0.2)
				(max_length 1)
				(best_width_ratio 0.9)
				(max_width 2)
				(curved_edges yes)
				(filter_ratio 0.9)
				(enabled yes)
				(allow_two_segments yes)
				(prefer_zone_connections yes)
			)
		)
	)
)
